(kicad_pcb
	(version 20260206)
	(generator "pcbnew")
	(generator_version "10.0")
	(general
		(thickness 1.6)
		(legacy_teardrops no)
	)
	(paper "A4")
	(title_block
		(title "Bryce Canyon_SCC_16316-1_OCP.brd")
		(comment 1 "Bryce Canyon / footprints 1307-1314 of 1561")
	)
	(layers
		(0 "F.Cu" signal "TOP")
		(4 "In1.Cu" signal "L2GND")
		(6 "In2.Cu" signal "L3")
		(8 "In3.Cu" signal "L4VCC")
		(10 "In4.Cu" signal "L5VCC")
		(12 "In5.Cu" signal "L6")
		(14 "In6.Cu" signal "L7GND")
		(2 "B.Cu" signal "BOTTOM")
		(9 "F.Adhes" user "F.Adhesive")
		(11 "B.Adhes" user "B.Adhesive")
		(13 "F.Paste" user "Package Geometry/Pastemask Top")
		(15 "B.Paste" user "Package Geometry/Pastemask Bottom")
		(5 "F.SilkS" user "Ref Des/Silkscreen Top")
		(7 "B.SilkS" user "Ref Des/Silkscreen Bottom")
		(1 "F.Mask" user "Board Geometry/Soldermask Top")
		(3 "B.Mask" user "Board Geometry/Soldermask Bottom")
		(17 "Dwgs.User" user "User.Drawings")
		(19 "Cmts.User" user "User.Comments")
		(21 "Eco1.User" user "User.Eco1")
		(23 "Eco2.User" user "User.Eco2")
		(25 "Edge.Cuts" user "Board Geometry/Outline")
		(27 "Margin" user)
		(31 "F.CrtYd" user "Package Geometry/Place Bound Top")
		(29 "B.CrtYd" user "Package Geometry/Place Bound Bottom")
		(35 "F.Fab" user "Ref Des/Assembly Top")
		(33 "B.Fab" user "Ref Des/Assembly Bottom")
	)
	(footprint ""
		(layer "B.Cu")
		(at 92.168472 -71.192898)
		(property "Reference" "C196"
			(at 0 0 0)
			(layer "B.SilkS")
			(hide yes)
			(effects
				(font
					(size 1.27 1.27)
				)
				(justify mirror)
			)
		)
		(property "Value" "SC22U6D3V3MX-9-GP-U"
			(at 0 -2.8194 0)
			(unlocked yes)
			(layer "B.Fab")
			(hide yes)
			(effects
				(font
					(size 1.016 1.016)
					(thickness 0.1524)
				)
				(justify mirror)
			)
		)
		(property "Device Type" "C603H40"
			(at 0 -4.3434 0)
			(unlocked yes)
			(layer "B.Fab")
			(hide yes)
			(effects
				(font
					(size 1.016 1.016)
					(thickness 0.1524)
				)
				(justify mirror)
			)
		)
		(duplicate_pad_numbers_are_jumpers no)
		(fp_line
			(start -0.508 0)
			(end 0.508 0)
			(stroke
				(width 0.2032)
				(type default)
			)
			(layer "B.SilkS")
		)
		(fp_rect
			(start 0.5842 1.3335)
			(end -0.5842 -1.3335)
			(stroke
				(width 0)
				(type default)
			)
			(fill no)
			(layer "B.CrtYd")
		)
		(fp_rect
			(start 0.5842 1.3335)
			(end -0.5842 -1.3335)
			(stroke
				(width 0)
				(type default)
			)
			(fill no)
			(layer "B.Fab")
		)
		(pad "1" smd custom
			(at 0 -0.762 180)
			(size 0.2159 0.2159)
			(layers "B.Cu" "B.Mask" "B.Paste")
			(net "SYSPLL_VDDA18")
			(options
				(clearance outline)
				(anchor circle)
			)
			(primitives
				(gr_poly
					(pts
						(arc
							(start -0.3302 0.4318)
							(mid -0.402042 0.402042)
							(end -0.4318 0.3302)
						)
						(arc
							(start -0.4318 -0.3302)
							(mid -0.402042 -0.402042)
							(end -0.3302 -0.4318)
						)
						(arc
							(start 0.3302 -0.4318)
							(mid 0.402042 -0.402042)
							(end 0.4318 -0.3302)
						)
						(arc
							(start 0.4318 0.3302)
							(mid 0.402042 0.402042)
							(end 0.3302 0.4318)
						)
					)
					(width 0)
					(fill yes)
				)
			)
		)
		(pad "2" smd custom
			(at 0 0.762 180)
			(size 0.2159 0.2159)
			(layers "B.Cu" "B.Mask" "B.Paste")
			(net "GND")
			(options
				(clearance outline)
				(anchor circle)
			)
			(primitives
				(gr_poly
					(pts
						(arc
							(start -0.3302 0.4318)
							(mid -0.402042 0.402042)
							(end -0.4318 0.3302)
						)
						(arc
							(start -0.4318 -0.3302)
							(mid -0.402042 -0.402042)
							(end -0.3302 -0.4318)
						)
						(arc
							(start 0.3302 -0.4318)
							(mid 0.402042 -0.402042)
							(end 0.4318 -0.3302)
						)
						(arc
							(start 0.4318 0.3302)
							(mid 0.402042 0.402042)
							(end 0.3302 0.4318)
						)
					)
					(width 0)
					(fill yes)
				)
			)
		)
	)
	(footprint ""
		(layer "B.Cu")
		(at 199.4789 -23.749 180)
		(property "Reference" "R239"
			(at 0 0 0)
			(layer "B.SilkS")
			(hide yes)
			(effects
				(font
					(size 1.27 1.27)
				)
				(justify mirror)
			)
		)
		(property "Value" "150R2F-1-GP"
			(at -0.064008 -3.993896 180)
			(unlocked yes)
			(layer "B.Fab")
			(hide yes)
			(effects
				(font
					(size 1.016 1.016)
					(thickness 0.1524)
				)
				(justify mirror)
			)
		)
		(property "Device Type" "R402H16"
			(at -0.064008 -5.517896 180)
			(unlocked yes)
			(layer "B.Fab")
			(hide yes)
			(effects
				(font
					(size 1.016 1.016)
					(thickness 0.1524)
				)
				(justify mirror)
			)
		)
		(duplicate_pad_numbers_are_jumpers no)
		(fp_line
			(start 0.508 -0.9398)
			(end 0.508 0.9398)
			(stroke
				(width 0.1524)
				(type default)
			)
			(layer "B.SilkS")
		)
		(fp_line
			(start -0.508 -0.9398)
			(end 0.508 -0.9398)
			(stroke
				(width 0.1524)
				(type default)
			)
			(layer "B.SilkS")
		)
		(fp_rect
			(start 0.508 0.9398)
			(end -0.508 -0.9398)
			(stroke
				(width 0)
				(type default)
			)
			(fill no)
			(layer "B.CrtYd")
		)
		(fp_rect
			(start 0.508 0.9398)
			(end -0.508 -0.9398)
			(stroke
				(width 0)
				(type default)
			)
			(fill no)
			(layer "B.Fab")
		)
		(pad "1" smd custom
			(at 0 -0.4445)
			(size 0.1397 0.1397)
			(layers "B.Cu" "B.Mask" "B.Paste")
			(net "P3V3")
			(options
				(clearance outline)
				(anchor circle)
			)
			(primitives
				(gr_poly
					(pts
						(arc
							(start -0.1778 0.2794)
							(mid -0.249642 0.249642)
							(end -0.2794 0.1778)
						)
						(arc
							(start -0.2794 -0.1778)
							(mid -0.249642 -0.249642)
							(end -0.1778 -0.2794)
						)
						(arc
							(start 0.1778 -0.2794)
							(mid 0.249642 -0.249642)
							(end 0.2794 -0.1778)
						)
						(arc
							(start 0.2794 0.1778)
							(mid 0.249642 0.249642)
							(end 0.1778 0.2794)
						)
					)
					(width 0)
					(fill yes)
				)
			)
		)
		(pad "2" smd custom
			(at 0 0.4445)
			(size 0.1397 0.1397)
			(layers "B.Cu" "B.Mask" "B.Paste")
			(net "SYS_ERROR_LED_R")
			(options
				(clearance outline)
				(anchor circle)
			)
			(primitives
				(gr_poly
					(pts
						(arc
							(start -0.1778 0.2794)
							(mid -0.249642 0.249642)
							(end -0.2794 0.1778)
						)
						(arc
							(start -0.2794 -0.1778)
							(mid -0.249642 -0.249642)
							(end -0.1778 -0.2794)
						)
						(arc
							(start 0.1778 -0.2794)
							(mid 0.249642 -0.249642)
							(end 0.2794 -0.1778)
						)
						(arc
							(start 0.2794 0.1778)
							(mid 0.249642 0.249642)
							(end 0.1778 0.2794)
						)
					)
					(width 0)
					(fill yes)
				)
			)
		)
	)
	(footprint ""
		(layer "B.Cu")
		(at 157.2768 -111.0996)
		(property "Reference" "C700"
			(at 0 0 0)
			(layer "B.SilkS")
			(hide yes)
			(effects
				(font
					(size 1.27 1.27)
				)
				(justify mirror)
			)
		)
		(property "Value" "SC10U16V5KX-7-GP-U"
			(at 0.0762 -6.1214 0)
			(unlocked yes)
			(layer "B.Fab")
			(hide yes)
			(effects
				(font
					(size 1.016 1.016)
					(thickness 0.1524)
				)
				(justify mirror)
			)
		)
		(property "Device Type" "C805H58"
			(at 0.0762 -8.1534 0)
			(unlocked yes)
			(layer "B.Fab")
			(hide yes)
			(effects
				(font
					(size 1.016 1.016)
					(thickness 0.1524)
				)
				(justify mirror)
			)
		)
		(duplicate_pad_numbers_are_jumpers no)
		(fp_line
			(start -0.635 0)
			(end 0.635 0)
			(stroke
				(width 0.508)
				(type default)
			)
			(layer "B.SilkS")
		)
		(fp_rect
			(start 0.9652 1.778)
			(end -0.9652 -1.778)
			(stroke
				(width 0)
				(type default)
			)
			(fill no)
			(layer "B.CrtYd")
		)
		(fp_poly
			(pts
				(xy 0.9652 -1.778) (xy -0.9652 -1.778) (xy -0.9652 1.778) (xy 0.9652 1.778)
			)
			(stroke
				(width 0)
				(type default)
			)
			(fill no)
			(layer "B.Fab")
		)
		(pad "1" smd rect
			(at 0 -0.9652 180)
			(size 1.397 1.143)
			(layers "B.Cu" "B.Mask" "B.Paste")
			(net "P12V_STBY_VIN_U11")
		)
		(pad "2" smd rect
			(at 0 0.9652 180)
			(size 1.397 1.143)
			(layers "B.Cu" "B.Mask" "B.Paste")
			(net "GND")
		)
	)
	(footprint ""
		(layer "B.Cu")
		(at 193.26098 -20.8026 90)
		(property "Reference" "R242"
			(at 0 0 90)
			(layer "B.SilkS")
			(hide yes)
			(effects
				(font
					(size 1.27 1.27)
				)
				(justify mirror)
			)
		)
		(property "Value" "4K7R2F-GP"
			(at -0.064008 -3.993896 90)
			(unlocked yes)
			(layer "B.Fab")
			(hide yes)
			(effects
				(font
					(size 1.016 1.016)
					(thickness 0.1524)
				)
				(justify mirror)
			)
		)
		(property "Device Type" "R402H16"
			(at -0.064008 -5.517896 90)
			(unlocked yes)
			(layer "B.Fab")
			(hide yes)
			(effects
				(font
					(size 1.016 1.016)
					(thickness 0.1524)
				)
				(justify mirror)
			)
		)
		(duplicate_pad_numbers_are_jumpers no)
		(fp_line
			(start 0.508 -0.9398)
			(end 0.508 0.9398)
			(stroke
				(width 0.1524)
				(type default)
			)
			(layer "B.SilkS")
		)
		(fp_line
			(start -0.508 -0.9398)
			(end 0.508 -0.9398)
			(stroke
				(width 0.1524)
				(type default)
			)
			(layer "B.SilkS")
		)
		(fp_rect
			(start 0.508 0.9398)
			(end -0.508 -0.9398)
			(stroke
				(width 0)
				(type default)
			)
			(fill no)
			(layer "B.CrtYd")
		)
		(fp_rect
			(start 0.508 0.9398)
			(end -0.508 -0.9398)
			(stroke
				(width 0)
				(type default)
			)
			(fill no)
			(layer "B.Fab")
		)
		(pad "1" smd custom
			(at 0 -0.4445 270)
			(size 0.1397 0.1397)
			(layers "B.Cu" "B.Mask" "B.Paste")
			(net "P1V8_C")
			(options
				(clearance outline)
				(anchor circle)
			)
			(primitives
				(gr_poly
					(pts
						(arc
							(start -0.1778 0.2794)
							(mid -0.249642 0.249642)
							(end -0.2794 0.1778)
						)
						(arc
							(start -0.2794 -0.1778)
							(mid -0.249642 -0.249642)
							(end -0.1778 -0.2794)
						)
						(arc
							(start 0.1778 -0.2794)
							(mid 0.249642 -0.249642)
							(end 0.2794 -0.1778)
						)
						(arc
							(start 0.2794 0.1778)
							(mid 0.249642 0.249642)
							(end 0.1778 0.2794)
						)
					)
					(width 0)
					(fill yes)
				)
			)
		)
		(pad "2" smd custom
			(at 0 0.4445 270)
			(size 0.1397 0.1397)
			(layers "B.Cu" "B.Mask" "B.Paste")
			(net "SYS_RST")
			(options
				(clearance outline)
				(anchor circle)
			)
			(primitives
				(gr_poly
					(pts
						(arc
							(start -0.1778 0.2794)
							(mid -0.249642 0.249642)
							(end -0.2794 0.1778)
						)
						(arc
							(start -0.2794 -0.1778)
							(mid -0.249642 -0.249642)
							(end -0.1778 -0.2794)
						)
						(arc
							(start 0.1778 -0.2794)
							(mid 0.249642 -0.249642)
							(end 0.2794 -0.1778)
						)
						(arc
							(start 0.2794 0.1778)
							(mid 0.249642 0.249642)
							(end 0.1778 0.2794)
						)
					)
					(width 0)
					(fill yes)
				)
			)
		)
	)
	(footprint ""
		(layer "B.Cu")
		(at 114.3 -70.3834 180)
		(property "Reference" "C171"
			(at 0 0 0)
			(layer "B.SilkS")
			(hide yes)
			(effects
				(font
					(size 1.27 1.27)
				)
				(justify mirror)
			)
		)
		(property "Value" "SCD1U6D3V1KX-GP"
			(at 2.8321 -1.7399 180)
			(unlocked yes)
			(layer "B.Fab")
			(hide yes)
			(effects
				(font
					(size 1.016 1.016)
					(thickness 0.1524)
				)
				(justify mirror)
			)
		)
		(property "Device Type" "C0201H13"
			(at 2.8321 -3.2639 180)
			(unlocked yes)
			(layer "B.Fab")
			(hide yes)
			(effects
				(font
					(size 1.016 1.016)
					(thickness 0.1524)
				)
				(justify mirror)
			)
		)
		(duplicate_pad_numbers_are_jumpers no)
		(fp_rect
			(start 0.2794 0.6477)
			(end -0.2794 -0.6477)
			(stroke
				(width 0)
				(type default)
			)
			(fill no)
			(layer "B.CrtYd")
		)
		(fp_rect
			(start 0.2794 0.6477)
			(end -0.2794 -0.6477)
			(stroke
				(width 0)
				(type default)
			)
			(fill no)
			(layer "B.Fab")
		)
		(pad "1" smd custom
			(at 0 -0.2794)
			(size 0.0762 0.0762)
			(layers "B.Cu" "B.Mask" "B.Paste")
			(net "P0V9")
			(options
				(clearance outline)
				(anchor circle)
			)
			(primitives
				(gr_poly
					(pts
						(arc
							(start 0.1524 0.127)
							(mid 0.137521 0.162921)
							(end 0.1016 0.1778)
						)
						(arc
							(start -0.1016 0.1778)
							(mid -0.137521 0.162921)
							(end -0.1524 0.127)
						)
						(arc
							(start -0.1524 -0.127)
							(mid -0.137521 -0.162921)
							(end -0.1016 -0.1778)
						)
						(arc
							(start 0.1016 -0.1778)
							(mid 0.137521 -0.162921)
							(end 0.1524 -0.127)
						)
					)
					(width 0)
					(fill yes)
				)
			)
		)
		(pad "2" smd custom
			(at 0 0.2794)
			(size 0.0762 0.0762)
			(layers "B.Cu" "B.Mask" "B.Paste")
			(net "GND")
			(options
				(clearance outline)
				(anchor circle)
			)
			(primitives
				(gr_poly
					(pts
						(arc
							(start 0.1524 0.127)
							(mid 0.137521 0.162921)
							(end 0.1016 0.1778)
						)
						(arc
							(start -0.1016 0.1778)
							(mid -0.137521 0.162921)
							(end -0.1524 0.127)
						)
						(arc
							(start -0.1524 -0.127)
							(mid -0.137521 -0.162921)
							(end -0.1016 -0.1778)
						)
						(arc
							(start 0.1016 -0.1778)
							(mid 0.137521 -0.162921)
							(end 0.1524 -0.127)
						)
					)
					(width 0)
					(fill yes)
				)
			)
		)
	)
	(footprint ""
		(layer "B.Cu")
		(at 124.2822 -63.5 -90)
		(property "Reference" "C258"
			(at 0 0 90)
			(layer "B.SilkS")
			(hide yes)
			(effects
				(font
					(size 1.27 1.27)
				)
				(justify mirror)
			)
		)
		(property "Value" "SCD1U6D3V1KX-GP"
			(at 2.8321 -1.7399 270)
			(unlocked yes)
			(layer "B.Fab")
			(hide yes)
			(effects
				(font
					(size 1.016 1.016)
					(thickness 0.1524)
				)
				(justify mirror)
			)
		)
		(property "Device Type" "C0201H13"
			(at 2.8321 -3.2639 270)
			(unlocked yes)
			(layer "B.Fab")
			(hide yes)
			(effects
				(font
					(size 1.016 1.016)
					(thickness 0.1524)
				)
				(justify mirror)
			)
		)
		(duplicate_pad_numbers_are_jumpers no)
		(fp_rect
			(start 0.2794 0.6477)
			(end -0.2794 -0.6477)
			(stroke
				(width 0)
				(type default)
			)
			(fill no)
			(layer "B.CrtYd")
		)
		(fp_rect
			(start 0.2794 0.6477)
			(end -0.2794 -0.6477)
			(stroke
				(width 0)
				(type default)
			)
			(fill no)
			(layer "B.Fab")
		)
		(pad "1" smd custom
			(at 0 -0.2794 90)
			(size 0.0762 0.0762)
			(layers "B.Cu" "B.Mask" "B.Paste")
			(net "GB_VDDA")
			(options
				(clearance outline)
				(anchor circle)
			)
			(primitives
				(gr_poly
					(pts
						(arc
							(start 0.1524 0.127)
							(mid 0.137521 0.162921)
							(end 0.1016 0.1778)
						)
						(arc
							(start -0.1016 0.1778)
							(mid -0.137521 0.162921)
							(end -0.1524 0.127)
						)
						(arc
							(start -0.1524 -0.127)
							(mid -0.137521 -0.162921)
							(end -0.1016 -0.1778)
						)
						(arc
							(start 0.1016 -0.1778)
							(mid 0.137521 -0.162921)
							(end 0.1524 -0.127)
						)
					)
					(width 0)
					(fill yes)
				)
			)
		)
		(pad "2" smd custom
			(at 0 0.2794 90)
			(size 0.0762 0.0762)
			(layers "B.Cu" "B.Mask" "B.Paste")
			(net "GND")
			(options
				(clearance outline)
				(anchor circle)
			)
			(primitives
				(gr_poly
					(pts
						(arc
							(start 0.1524 0.127)
							(mid 0.137521 0.162921)
							(end 0.1016 0.1778)
						)
						(arc
							(start -0.1016 0.1778)
							(mid -0.137521 0.162921)
							(end -0.1524 0.127)
						)
						(arc
							(start -0.1524 -0.127)
							(mid -0.137521 -0.162921)
							(end -0.1016 -0.1778)
						)
						(arc
							(start 0.1016 -0.1778)
							(mid 0.137521 -0.162921)
							(end 0.1524 -0.127)
						)
					)
					(width 0)
					(fill yes)
				)
			)
		)
	)
	(footprint ""
		(layer "B.Cu")
		(at 200.179178 -31.849822)
		(property "Reference" "C363"
			(at 0 0 0)
			(layer "B.SilkS")
			(hide yes)
			(effects
				(font
					(size 1.27 1.27)
				)
				(justify mirror)
			)
		)
		(property "Value" "SC22U6D3V3MX-9-GP-U"
			(at 0 -2.8194 0)
			(unlocked yes)
			(layer "B.Fab")
			(hide yes)
			(effects
				(font
					(size 1.016 1.016)
					(thickness 0.1524)
				)
				(justify mirror)
			)
		)
		(property "Device Type" "C603H40"
			(at 0 -4.3434 0)
			(unlocked yes)
			(layer "B.Fab")
			(hide yes)
			(effects
				(font
					(size 1.016 1.016)
					(thickness 0.1524)
				)
				(justify mirror)
			)
		)
		(duplicate_pad_numbers_are_jumpers no)
		(fp_line
			(start -0.508 0)
			(end 0.508 0)
			(stroke
				(width 0.2032)
				(type default)
			)
			(layer "B.SilkS")
		)
		(fp_rect
			(start 0.5842 1.3335)
			(end -0.5842 -1.3335)
			(stroke
				(width 0)
				(type default)
			)
			(fill no)
			(layer "B.CrtYd")
		)
		(fp_rect
			(start 0.5842 1.3335)
			(end -0.5842 -1.3335)
			(stroke
				(width 0)
				(type default)
			)
			(fill no)
			(layer "B.Fab")
		)
		(pad "1" smd custom
			(at 0 -0.762 180)
			(size 0.2159 0.2159)
			(layers "B.Cu" "B.Mask" "B.Paste")
			(net "PLL_VDD")
			(options
				(clearance outline)
				(anchor circle)
			)
			(primitives
				(gr_poly
					(pts
						(arc
							(start -0.3302 0.4318)
							(mid -0.402042 0.402042)
							(end -0.4318 0.3302)
						)
						(arc
							(start -0.4318 -0.3302)
							(mid -0.402042 -0.402042)
							(end -0.3302 -0.4318)
						)
						(arc
							(start 0.3302 -0.4318)
							(mid 0.402042 -0.402042)
							(end 0.4318 -0.3302)
						)
						(arc
							(start 0.4318 0.3302)
							(mid 0.402042 0.402042)
							(end 0.3302 0.4318)
						)
					)
					(width 0)
					(fill yes)
				)
			)
		)
		(pad "2" smd custom
			(at 0 0.762 180)
			(size 0.2159 0.2159)
			(layers "B.Cu" "B.Mask" "B.Paste")
			(net "GND")
			(options
				(clearance outline)
				(anchor circle)
			)
			(primitives
				(gr_poly
					(pts
						(arc
							(start -0.3302 0.4318)
							(mid -0.402042 0.402042)
							(end -0.4318 0.3302)
						)
						(arc
							(start -0.4318 -0.3302)
							(mid -0.402042 -0.402042)
							(end -0.3302 -0.4318)
						)
						(arc
							(start 0.3302 -0.4318)
							(mid 0.402042 -0.402042)
							(end 0.4318 -0.3302)
						)
						(arc
							(start 0.4318 0.3302)
							(mid 0.402042 0.402042)
							(end 0.3302 0.4318)
						)
					)
					(width 0)
					(fill yes)
				)
			)
		)
	)
	(footprint ""
		(layer "B.Cu")
		(at 175.124872 -63.09487 180)
		(property "Reference" "R546"
			(at 0 0 0)
			(layer "B.SilkS")
			(hide yes)
			(effects
				(font
					(size 1.27 1.27)
				)
				(justify mirror)
			)
		)
		(property "Value" "4K7R2F-GP"
			(at -0.064008 -3.993896 180)
			(unlocked yes)
			(layer "B.Fab")
			(hide yes)
			(effects
				(font
					(size 1.016 1.016)
					(thickness 0.1524)
				)
				(justify mirror)
			)
		)
		(property "Device Type" "R402H16"
			(at -0.064008 -5.517896 180)
			(unlocked yes)
			(layer "B.Fab")
			(hide yes)
			(effects
				(font
					(size 1.016 1.016)
					(thickness 0.1524)
				)
				(justify mirror)
			)
		)
		(duplicate_pad_numbers_are_jumpers no)
		(fp_line
			(start 0.508 -0.9398)
			(end 0.508 0.9398)
			(stroke
				(width 0.1524)
				(type default)
			)
			(layer "B.SilkS")
		)
		(fp_line
			(start -0.508 -0.9398)
			(end 0.508 -0.9398)
			(stroke
				(width 0.1524)
				(type default)
			)
			(layer "B.SilkS")
		)
		(fp_rect
			(start 0.508 0.9398)
			(end -0.508 -0.9398)
			(stroke
				(width 0)
				(type default)
			)
			(fill no)
			(layer "B.CrtYd")
		)
		(fp_rect
			(start 0.508 0.9398)
			(end -0.508 -0.9398)
			(stroke
				(width 0)
				(type default)
			)
			(fill no)
			(layer "B.Fab")
		)
		(pad "1" smd custom
			(at 0 -0.4445)
			(size 0.1397 0.1397)
			(layers "B.Cu" "B.Mask" "B.Paste")
			(net "P1V8_C")
			(options
				(clearance outline)
				(anchor circle)
			)
			(primitives
				(gr_poly
					(pts
						(arc
							(start -0.1778 0.2794)
							(mid -0.249642 0.249642)
							(end -0.2794 0.1778)
						)
						(arc
							(start -0.2794 -0.1778)
							(mid -0.249642 -0.249642)
							(end -0.1778 -0.2794)
						)
						(arc
							(start 0.1778 -0.2794)
							(mid 0.249642 -0.249642)
							(end 0.2794 -0.1778)
						)
						(arc
							(start 0.2794 0.1778)
							(mid 0.249642 0.249642)
							(end 0.1778 0.2794)
						)
					)
					(width 0)
					(fill yes)
				)
			)
		)
		(pad "2" smd custom
			(at 0 0.4445)
			(size 0.1397 0.1397)
			(layers "B.Cu" "B.Mask" "B.Paste")
			(net "IOC_RESET_N")
			(options
				(clearance outline)
				(anchor circle)
			)
			(primitives
				(gr_poly
					(pts
						(arc
							(start -0.1778 0.2794)
							(mid -0.249642 0.249642)
							(end -0.2794 0.1778)
						)
						(arc
							(start -0.2794 -0.1778)
							(mid -0.249642 -0.249642)
							(end -0.1778 -0.2794)
						)
						(arc
							(start 0.1778 -0.2794)
							(mid 0.249642 -0.249642)
							(end 0.2794 -0.1778)
						)
						(arc
							(start 0.2794 0.1778)
							(mid 0.249642 0.249642)
							(end 0.1778 0.2794)
						)
					)
					(width 0)
					(fill yes)
				)
			)
		)
	)
)
